(kicad_pcb
	(version 20260206)
	(generator "pcbnew")
	(generator_version "10.0")
	(general
		(thickness 1.6)
		(legacy_teardrops no)
	)
	(paper "A4")
	(title_block
		(title "Bryce Canyon_F.DPB_16315-1-OCP.brd")
		(comment 1 "Bryce Canyon / footprints 45-47 of 2223")
	)
	(layers
		(0 "F.Cu" signal "TOP")
		(4 "In1.Cu" signal "L2GND")
		(6 "In2.Cu" signal "L3")
		(8 "In3.Cu" signal "L4GND")
		(10 "In4.Cu" signal "L5")
		(12 "In5.Cu" signal "L6VCC")
		(14 "In6.Cu" signal "L7VCC")
		(16 "In7.Cu" signal "L8")
		(18 "In8.Cu" signal "L9GND")
		(20 "In9.Cu" signal "L10")
		(22 "In10.Cu" signal "L11GND")
		(2 "B.Cu" signal "BOTTOM")
		(9 "F.Adhes" user "F.Adhesive")
		(11 "B.Adhes" user "B.Adhesive")
		(13 "F.Paste" user "Package Geometry/Pastemask Top")
		(15 "B.Paste" user "Package Geometry/Pastemask Bottom")
		(5 "F.SilkS" user "Ref Des/Silkscreen Top")
		(7 "B.SilkS" user "Ref Des/Silkscreen Bottom")
		(1 "F.Mask" user "Board Geometry/Soldermask Top")
		(3 "B.Mask" user "Board Geometry/Soldermask Bottom")
		(17 "Dwgs.User" user "User.Drawings")
		(19 "Cmts.User" user "User.Comments")
		(21 "Eco1.User" user "User.Eco1")
		(23 "Eco2.User" user "User.Eco2")
		(25 "Edge.Cuts" user "Board Geometry/Outline")
		(27 "Margin" user)
		(31 "F.CrtYd" user "Package Geometry/Place Bound Top")
		(29 "B.CrtYd" user "Package Geometry/Place Bound Bottom")
		(35 "F.Fab" user "Ref Des/Assembly Top")
		(33 "B.Fab" user "Ref Des/Assembly Bottom")
	)
	(footprint ""
		(layer "F.Cu")
		(at 59.749944 -57.909968 -90)
		(property "Reference" "HDDSAS25"
			(at 0 0 270)
			(layer "F.SilkS")
			(hide yes)
			(effects
				(font
					(size 1.27 1.27)
				)
			)
		)
		(property "Value" "SKT-SAS15P-14P-45-GP"
			(at -20.7645 -8.9789 270)
			(unlocked yes)
			(layer "F.Fab")
			(hide yes)
			(effects
				(font
					(size 1.016 1.016)
					(thickness 0.1524)
				)
			)
		)
		(property "Device Type" "10120818-001C-TRLF"
			(at -20.7645 -10.5029 270)
			(unlocked yes)
			(layer "F.Fab")
			(hide yes)
			(effects
				(font
					(size 1.016 1.016)
					(thickness 0.1524)
				)
			)
		)
		(duplicate_pad_numbers_are_jumpers no)
		(fp_line
			(start 1.651 4.2926)
			(end 1.651 3.0099)
			(stroke
				(width 0.1524)
				(type default)
			)
			(layer "F.SilkS")
		)
		(fp_line
			(start 8.509 4.2926)
			(end 1.651 4.2926)
			(stroke
				(width 0.1524)
				(type default)
			)
			(layer "F.SilkS")
		)
		(fp_line
			(start -23.4188 3.0099)
			(end -23.4188 -3.2512)
			(stroke
				(width 0.1524)
				(type default)
			)
			(layer "F.SilkS")
		)
		(fp_line
			(start 1.651 3.0099)
			(end -23.4188 3.0099)
			(stroke
				(width 0.1524)
				(type default)
			)
			(layer "F.SilkS")
		)
		(fp_line
			(start 8.509 3.0099)
			(end 8.509 4.2926)
			(stroke
				(width 0.1524)
				(type default)
			)
			(layer "F.SilkS")
		)
		(fp_line
			(start 23.4188 3.0099)
			(end 8.509 3.0099)
			(stroke
				(width 0.1524)
				(type default)
			)
			(layer "F.SilkS")
		)
		(fp_line
			(start -23.4188 -3.2512)
			(end 23.4188 -3.2512)
			(stroke
				(width 0.1524)
				(type default)
			)
			(layer "F.SilkS")
		)
		(fp_line
			(start 23.4188 -3.2512)
			(end 23.4188 3.0099)
			(stroke
				(width 0.1524)
				(type default)
			)
			(layer "F.SilkS")
		)
		(fp_line
			(start 15.5067 -3.3401)
			(end 16.2687 -3.3401)
			(stroke
				(width 0.3302)
				(type default)
			)
			(layer "F.SilkS")
		)
		(fp_poly
			(pts
				(xy 15.868904 -3.230372) (xy 16.503904 -3.865372) (xy 15.233904 -3.865372)
			)
			(stroke
				(width 0)
				(type default)
			)
			(fill yes)
			(layer "F.SilkS")
		)
		(fp_poly
			(pts
				(xy -22.8727 -2.7559) (xy 22.8727 -2.7559) (xy 22.8727 2.7559) (xy 8.255 2.7559) (xy 8.255 3.5179)
				(xy 1.905 3.5179) (xy 1.905 2.7559) (xy -22.8727 2.7559)
			)
			(stroke
				(width 0)
				(type default)
			)
			(fill no)
			(layer "F.CrtYd")
		)
		(fp_poly
			(pts
				(xy 1.397 4.5466) (xy 1.397 3.2639) (xy -23.6728 3.2639) (xy -23.6728 -3.5052) (xy 23.6728 -3.5052)
				(xy 23.6728 -0.00635) (xy 22.8727 -0.00635) (xy 22.8727 -2.7559) (xy -22.8727 -2.7559) (xy -22.8727 2.7559)
				(xy 1.905 2.7559) (xy 1.905 3.5179) (xy 8.255 3.5179) (xy 8.255 2.7559) (xy 22.8727 2.7559) (xy 22.8727 0.00635)
				(xy 23.6728 0.00635) (xy 23.6728 3.2639) (xy 8.763 3.2639) (xy 8.763 4.5466)
			)
			(stroke
				(width 0)
				(type default)
			)
			(fill no)
			(layer "F.CrtYd")
		)
		(fp_poly
			(pts
				(xy 1.397 4.5466) (xy 1.397 3.2639) (xy -23.6728 3.2639) (xy -23.6728 -3.5052) (xy 23.6728 -3.5052)
				(xy 23.6728 3.2639) (xy 8.763 3.2639) (xy 8.763 4.5466)
			)
			(stroke
				(width 0)
				(type default)
			)
			(fill no)
			(layer "F.Fab")
		)
		(pad "" np_thru_hole circle
			(at -18.874994 0 270)
			(size 0.254 0.254)
			(drill 1.3462)
			(layers "*.Cu" "*.Mask")
			(clearance 0.9017)
			(thermal_gap 0.9017)
		)
		(pad "" np_thru_hole circle
			(at 18.874994 0 270)
			(size 0.254 0.254)
			(drill 0.9398)
			(layers "*.Cu" "*.Mask")
			(clearance 0.6985)
			(thermal_gap 0.6985)
		)
		(pad "G1" smd rect
			(at 21.874988 0 270)
			(size 2.5908 2.5908)
			(layers "F.Cu" "F.Mask" "F.Paste")
			(net "GND")
		)
		(pad "G2" smd rect
			(at -21.874988 0 270)
			(size 2.5908 2.5908)
			(layers "F.Cu" "F.Mask" "F.Paste")
			(net "GND")
		)
		(pad "P1" smd rect
			(at 1.905 -1.82499 270)
			(size 0.6096 2.3622)
			(layers "F.Cu" "F.Mask" "F.Paste")
			(net "Net_2086")
		)
		(pad "P2" smd rect
			(at 0.635 -1.82499 270)
			(size 0.6096 2.3622)
			(layers "F.Cu" "F.Mask" "F.Paste")
			(net "Net_2087")
		)
		(pad "P3" smd rect
			(at -0.635 -1.82499 270)
			(size 0.6096 2.3622)
			(layers "F.Cu" "F.Mask" "F.Paste")
			(net "Net_2088")
		)
		(pad "P4" smd rect
			(at -1.905 -1.82499 270)
			(size 0.6096 2.3622)
			(layers "F.Cu" "F.Mask" "F.Paste")
			(net "GND")
		)
		(pad "P5" smd rect
			(at -3.175 -1.82499 270)
			(size 0.6096 2.3622)
			(layers "F.Cu" "F.Mask" "F.Paste")
			(net "HDD_PRSNT_25")
		)
		(pad "P6" smd rect
			(at -4.445 -1.82499 270)
			(size 0.6096 2.3622)
			(layers "F.Cu" "F.Mask" "F.Paste")
			(net "GND")
		)
		(pad "P7" smd rect
			(at -5.715 -1.82499 270)
			(size 0.6096 2.3622)
			(layers "F.Cu" "F.Mask" "F.Paste")
			(net "5V_PRE_25")
		)
		(pad "P8" smd rect
			(at -6.985 -1.82499 270)
			(size 0.6096 2.3622)
			(layers "F.Cu" "F.Mask" "F.Paste")
			(net "P5V_HDD25")
		)
		(pad "P9" smd rect
			(at -8.255 -1.82499 270)
			(size 0.6096 2.3622)
			(layers "F.Cu" "F.Mask" "F.Paste")
			(net "P5V_HDD25")
		)
		(pad "P10" smd rect
			(at -9.525 -1.82499 270)
			(size 0.6096 2.3622)
			(layers "F.Cu" "F.Mask" "F.Paste")
			(net "GND")
		)
		(pad "P11" smd rect
			(at -10.795 -1.82499 270)
			(size 0.6096 2.3622)
			(layers "F.Cu" "F.Mask" "F.Paste")
			(net "ACT_HDD_25")
		)
		(pad "P12" smd rect
			(at -12.065 -1.82499 270)
			(size 0.6096 2.3622)
			(layers "F.Cu" "F.Mask" "F.Paste")
			(net "GND")
		)
		(pad "P13" smd rect
			(at -13.335 -1.82499 270)
			(size 0.6096 2.3622)
			(layers "F.Cu" "F.Mask" "F.Paste")
			(net "12V_PRE_25")
		)
		(pad "P14" smd rect
			(at -14.605 -1.82499 270)
			(size 0.6096 2.3622)
			(layers "F.Cu" "F.Mask" "F.Paste")
			(net "P12V_HDD25")
		)
		(pad "P15" smd rect
			(at -15.875 -1.82499 270)
			(size 0.6096 2.3622)
			(layers "F.Cu" "F.Mask" "F.Paste")
			(net "P12V_HDD25")
		)
		(pad "S1" smd rect
			(at 15.875 -1.82499 270)
			(size 0.6096 2.3622)
			(layers "F.Cu" "F.Mask" "F.Paste")
			(net "GND")
		)
		(pad "S2" smd rect
			(at 14.605 -1.82499 270)
			(size 0.6096 2.3622)
			(layers "F.Cu" "F.Mask" "F.Paste")
			(net "SAS_HDD_RX_P25")
		)
		(pad "S3" smd rect
			(at 13.335 -1.82499 270)
			(size 0.6096 2.3622)
			(layers "F.Cu" "F.Mask" "F.Paste")
			(net "SAS_HDD_RX_N25")
		)
		(pad "S4" smd rect
			(at 12.065 -1.82499 270)
			(size 0.6096 2.3622)
			(layers "F.Cu" "F.Mask" "F.Paste")
			(net "GND")
		)
		(pad "S5" smd rect
			(at 10.795 -1.82499 270)
			(size 0.6096 2.3622)
			(layers "F.Cu" "F.Mask" "F.Paste")
			(net "PHY_DRV_A_TO_SCC_A_25_DN")
		)
		(pad "S6" smd rect
			(at 9.525 -1.82499 270)
			(size 0.6096 2.3622)
			(layers "F.Cu" "F.Mask" "F.Paste")
			(net "PHY_DRV_A_TO_SCC_A_25_DP")
		)
		(pad "S7" smd rect
			(at 8.255 -1.82499 270)
			(size 0.6096 2.3622)
			(layers "F.Cu" "F.Mask" "F.Paste")
			(net "GND")
		)
		(pad "S8" smd rect
			(at 7.480046 2.845054 270)
			(size 0.508 2.3622)
			(layers "F.Cu" "F.Mask" "F.Paste")
			(net "GND")
		)
		(pad "S9" smd rect
			(at 6.679946 2.845054 270)
			(size 0.508 2.3622)
			(layers "F.Cu" "F.Mask" "F.Paste")
			(net "Net_463")
		)
		(pad "S10" smd rect
			(at 5.8801 2.845054 270)
			(size 0.508 2.3622)
			(layers "F.Cu" "F.Mask" "F.Paste")
			(net "Net_355")
		)
		(pad "S11" smd rect
			(at 5.08 2.845054 270)
			(size 0.508 2.3622)
			(layers "F.Cu" "F.Mask" "F.Paste")
			(net "GND")
		)
		(pad "S12" smd rect
			(at 4.2799 2.845054 270)
			(size 0.508 2.3622)
			(layers "F.Cu" "F.Mask" "F.Paste")
			(net "Net_391")
		)
		(pad "S13" smd rect
			(at 3.480054 2.845054 270)
			(size 0.508 2.3622)
			(layers "F.Cu" "F.Mask" "F.Paste")
			(net "Net_427")
		)
		(pad "S14" smd rect
			(at 2.679954 2.845054 270)
			(size 0.508 2.3622)
			(layers "F.Cu" "F.Mask" "F.Paste")
			(net "GND")
		)
		(zone
			(layer "F.Cu")
			(hatch none 0.5)
			(connect_pads
				(clearance 0)
			)
			(min_thickness 0.25)
			(keepout
				(tracks allowed)
				(vias not_allowed)
				(pads allowed)
				(copperpour not_allowed)
				(footprints allowed)
			)
			(placement
				(enabled no)
				(sheetname "")
			)
			(fill
				(thermal_gap 0.5)
				(thermal_bridge_width 0.5)
				(island_removal_mode 0)
			)
			(polygon
				(pts
					(xy 63.407544 -74.648568) (xy 56.333644 -74.648568) (xy 56.333644 -81.582768) (xy 57.438544 -81.582768)
					(xy 57.438544 -77.467968) (xy 62.061344 -77.467968) (xy 62.061344 -81.582768) (xy 63.407544 -81.582768)
				)
			)
		)
		(zone
			(layer "F.Cu")
			(hatch none 0.5)
			(connect_pads
				(clearance 0)
			)
			(min_thickness 0.25)
			(keepout
				(tracks not_allowed)
				(vias allowed)
				(pads allowed)
				(copperpour not_allowed)
				(footprints allowed)
			)
			(placement
				(enabled no)
				(sheetname "")
			)
			(fill
				(thermal_gap 0.5)
				(thermal_bridge_width 0.5)
				(island_removal_mode 0)
			)
			(polygon
				(pts
					(xy 63.407544 -74.648568) (xy 56.333644 -74.648568) (xy 56.333644 -81.582768) (xy 57.438544 -81.582768)
					(xy 57.438544 -77.467968) (xy 62.061344 -77.467968) (xy 62.061344 -81.582768) (xy 63.407544 -81.582768)
				)
			)
		)
		(zone
			(layer "F.Cu")
			(hatch none 0.5)
			(connect_pads
				(clearance 0)
			)
			(min_thickness 0.25)
			(keepout
				(tracks allowed)
				(vias not_allowed)
				(pads allowed)
				(copperpour not_allowed)
				(footprints allowed)
			)
			(placement
				(enabled no)
				(sheetname "")
			)
			(fill
				(thermal_gap 0.5)
				(thermal_bridge_width 0.5)
				(island_removal_mode 0)
			)
			(polygon
				(pts
					(xy 63.407544 -41.171368) (xy 56.333644 -41.171368) (xy 56.333644 -34.237168) (xy 57.438544 -34.237168)
					(xy 57.438544 -38.351968) (xy 62.061344 -38.351968) (xy 62.061344 -34.237168) (xy 63.407544 -34.237168)
				)
			)
		)
		(zone
			(layer "F.Cu")
			(hatch none 0.5)
			(connect_pads
				(clearance 0)
			)
			(min_thickness 0.25)
			(keepout
				(tracks not_allowed)
				(vias allowed)
				(pads allowed)
				(copperpour not_allowed)
				(footprints allowed)
			)
			(placement
				(enabled no)
				(sheetname "")
			)
			(fill
				(thermal_gap 0.5)
				(thermal_bridge_width 0.5)
				(island_removal_mode 0)
			)
			(polygon
				(pts
					(xy 63.407544 -41.171368) (xy 56.333644 -41.171368) (xy 56.333644 -34.237168) (xy 57.438544 -34.237168)
					(xy 57.438544 -38.351968) (xy 62.061344 -38.351968) (xy 62.061344 -34.237168) (xy 63.407544 -34.237168)
				)
			)
		)
		(zone
			(layers "F.Cu" "B.Cu" "In1.Cu" "In2.Cu" "In3.Cu" "In4.Cu" "In5.Cu" "In6.Cu"
				"In7.Cu" "In8.Cu" "In9.Cu" "In10.Cu"
			)
			(hatch none 0.5)
			(connect_pads
				(clearance 0)
			)
			(min_thickness 0.25)
			(keepout
				(tracks not_allowed)
				(vias allowed)
				(pads allowed)
				(copperpour not_allowed)
				(footprints allowed)
			)
			(placement
				(enabled no)
				(sheetname "")
			)
			(fill
				(thermal_gap 0.5)
				(thermal_bridge_width 0.5)
				(island_removal_mode 0)
			)
			(polygon
				(pts
					(arc
						(start 60.524644 -39.034974)
						(mid 58.975244 -39.034974)
						(end 60.524644 -39.034974)
					)
				)
			)
		)
		(zone
			(layers "F.Cu" "B.Cu" "In1.Cu" "In2.Cu" "In3.Cu" "In4.Cu" "In5.Cu" "In6.Cu"
				"In7.Cu" "In8.Cu" "In9.Cu" "In10.Cu"
			)
			(hatch none 0.5)
			(connect_pads
				(clearance 0)
			)
			(min_thickness 0.25)
			(keepout
				(tracks not_allowed)
				(vias allowed)
				(pads allowed)
				(copperpour not_allowed)
				(footprints allowed)
			)
			(placement
				(enabled no)
				(sheetname "")
			)
			(fill
				(thermal_gap 0.5)
				(thermal_bridge_width 0.5)
				(island_removal_mode 0)
			)
			(polygon
				(pts
					(arc
						(start 60.727844 -76.784962)
						(mid 58.772044 -76.784962)
						(end 60.727844 -76.784962)
					)
				)
			)
		)
	)
	(footprint ""
		(layer "F.Cu")
		(at 433.359052 -287.851342 90)
		(property "Reference" "C166"
			(at 0 0 90)
			(layer "F.SilkS")
			(hide yes)
			(effects
				(font
					(size 1.27 1.27)
				)
			)
		)
		(property "Value" "SCD033U25V2KX-GP"
			(at 1.1811 -2.7051 90)
			(unlocked yes)
			(layer "F.Fab")
			(hide yes)
			(effects
				(font
					(size 1.016 1.016)
					(thickness 0.1524)
				)
			)
		)
		(property "Device Type" "C402H22"
			(at 1.1811 -4.2291 90)
			(unlocked yes)
			(layer "F.Fab")
			(hide yes)
			(effects
				(font
					(size 1.016 1.016)
					(thickness 0.1524)
				)
			)
		)
		(duplicate_pad_numbers_are_jumpers no)
		(fp_rect
			(start -0.4318 0.9525)
			(end 0.4318 -0.9525)
			(stroke
				(width 0)
				(type default)
			)
			(fill no)
			(layer "F.CrtYd")
		)
		(fp_rect
			(start -0.4318 0.9525)
			(end 0.4318 -0.9525)
			(stroke
				(width 0)
				(type default)
			)
			(fill no)
			(layer "F.Fab")
		)
		(pad "1" smd custom
			(at 0 -0.4445 90)
			(size 0.1524 0.1524)
			(layers "F.Cu" "F.Mask" "F.Paste")
			(net "P12V_A")
			(options
				(clearance outline)
				(anchor circle)
			)
			(primitives
				(gr_poly
					(pts
						(arc
							(start 0.3048 -0.2032)
							(mid 0.275042 -0.275042)
							(end 0.2032 -0.3048)
						)
						(arc
							(start -0.2032 -0.3048)
							(mid -0.275042 -0.275042)
							(end -0.3048 -0.2032)
						)
						(arc
							(start -0.3048 0.2032)
							(mid -0.275042 0.275042)
							(end -0.2032 0.3048)
						)
						(arc
							(start 0.2032 0.3048)
							(mid 0.275042 0.275042)
							(end 0.3048 0.2032)
						)
					)
					(width 0)
					(fill yes)
				)
			)
		)
		(pad "2" smd custom
			(at 0 0.4445 90)
			(size 0.1524 0.1524)
			(layers "F.Cu" "F.Mask" "F.Paste")
			(net "SW_HDD_N9")
			(options
				(clearance outline)
				(anchor circle)
			)
			(primitives
				(gr_poly
					(pts
						(arc
							(start 0.3048 -0.2032)
							(mid 0.275042 -0.275042)
							(end 0.2032 -0.3048)
						)
						(arc
							(start -0.2032 -0.3048)
							(mid -0.275042 -0.275042)
							(end -0.3048 -0.2032)
						)
						(arc
							(start -0.3048 0.2032)
							(mid -0.275042 0.275042)
							(end -0.2032 0.3048)
						)
						(arc
							(start 0.2032 0.3048)
							(mid 0.275042 0.275042)
							(end 0.3048 0.2032)
						)
					)
					(width 0)
					(fill yes)
				)
			)
		)
	)
	(footprint ""
		(layer "F.Cu")
		(at 298.7294 -70.0786)
		(property "Reference" "R626"
			(at 0 0 0)
			(layer "F.SilkS")
			(hide yes)
			(effects
				(font
					(size 1.27 1.27)
				)
			)
		)
		(property "Value" "4K7R2F-GP"
			(at 0.064008 -3.993896 0)
			(unlocked yes)
			(layer "F.Fab")
			(hide yes)
			(effects
				(font
					(size 1.016 1.016)
					(thickness 0.1524)
				)
			)
		)
		(property "Device Type" "R402H16"
			(at 0.064008 -5.517896 0)
			(unlocked yes)
			(layer "F.Fab")
			(hide yes)
			(effects
				(font
					(size 1.016 1.016)
					(thickness 0.1524)
				)
			)
		)
		(duplicate_pad_numbers_are_jumpers no)
		(fp_line
			(start -0.508 -0.9398)
			(end -0.508 0.9398)
			(stroke
				(width 0.1524)
				(type default)
			)
			(layer "F.SilkS")
		)
		(fp_line
			(start 0.508 -0.9398)
			(end -0.508 -0.9398)
			(stroke
				(width 0.1524)
				(type default)
			)
			(layer "F.SilkS")
		)
		(fp_rect
			(start -0.508 0.9398)
			(end 0.508 -0.9398)
			(stroke
				(width 0)
				(type default)
			)
			(fill no)
			(layer "F.CrtYd")
		)
		(fp_rect
			(start -0.508 0.9398)
			(end 0.508 -0.9398)
			(stroke
				(width 0)
				(type default)
			)
			(fill no)
			(layer "F.Fab")
		)
		(pad "1" smd custom
			(at 0 -0.4445)
			(size 0.1397 0.1397)
			(layers "F.Cu" "F.Mask" "F.Paste")
			(net "I2C_BMC_B_COMP_B_SCL")
			(options
				(clearance outline)
				(anchor circle)
			)
			(primitives
				(gr_poly
					(pts
						(arc
							(start -0.1778 -0.2794)
							(mid -0.249642 -0.249642)
							(end -0.2794 -0.1778)
						)
						(arc
							(start -0.2794 0.1778)
							(mid -0.249642 0.249642)
							(end -0.1778 0.2794)
						)
						(arc
							(start 0.1778 0.2794)
							(mid 0.249642 0.249642)
							(end 0.2794 0.1778)
						)
						(arc
							(start 0.2794 -0.1778)
							(mid 0.249642 -0.249642)
							(end 0.1778 -0.2794)
						)
					)
					(width 0)
					(fill yes)
				)
			)
		)
		(pad "2" smd custom
			(at 0 0.4445)
			(size 0.1397 0.1397)
			(layers "F.Cu" "F.Mask" "F.Paste")
			(net "P3V3_STBY_B")
			(options
				(clearance outline)
				(anchor circle)
			)
			(primitives
				(gr_poly
					(pts
						(arc
							(start -0.1778 -0.2794)
							(mid -0.249642 -0.249642)
							(end -0.2794 -0.1778)
						)
						(arc
							(start -0.2794 0.1778)
							(mid -0.249642 0.249642)
							(end -0.1778 0.2794)
						)
						(arc
							(start 0.1778 0.2794)
							(mid 0.249642 0.249642)
							(end 0.2794 0.1778)
						)
						(arc
							(start 0.2794 -0.1778)
							(mid 0.249642 -0.249642)
							(end 0.1778 -0.2794)
						)
					)
					(width 0)
					(fill yes)
				)
			)
		)
	)
)
